# T6G (Grand Teton) — schematic netlist excerpt (pin names and nets, part order shuffled) for the footprints in the layout excerpt that follows; sources: Cadence DE-HDL packaged netlist, KiCad conversion of 04192023_DAF0TMB3IC0_F0TG_MB_C_brd_V02_OCP.brd

C2167  Q_CAP  22UF 4V 20% X6S  pkg C0402  page 69 : A = PVDDCR_CPU0_P0 ; B = GND
C539  Q_CAP  1UF 4V 20% X6S  pkg 0201  page 279 : A = P0V9_CPU0_RT0_2A ; B = GND
C2316  Q_CAP  22UF 4V 20% X6S  pkg C0402  page 73 : A = PVDDCR_CPU0_P1 ; B = GND

(kicad_pcb
	(version 20260206)
	(generator "pcbnew")
	(generator_version "10.0")
	(general
		(thickness 1.6)
		(legacy_teardrops no)
	)
	(paper "A4")
	(title_block
		(title "04192023_DAF0TMB3IC0_F0TG_MB_C_brd_V02_OCP.brd")
		(comment 1 "Grand Teton / footprints 6726-6728 of 8354")
	)
	(layers
		(0 "F.Cu" signal "TOP")
		(4 "In1.Cu" signal "GND")
		(6 "In2.Cu" signal "IN1")
		(8 "In3.Cu" signal "GND1")
		(10 "In4.Cu" signal "IN2")
		(12 "In5.Cu" signal "GND2")
		(14 "In6.Cu" signal "IN3")
		(16 "In7.Cu" signal "GND3")
		(18 "In8.Cu" signal "VCC")
		(20 "In9.Cu" signal "VCC1")
		(22 "In10.Cu" signal "GND4")
		(24 "In11.Cu" signal "IN4")
		(26 "In12.Cu" signal "GND5")
		(28 "In13.Cu" signal "IN5")
		(30 "In14.Cu" signal "GND6")
		(32 "In15.Cu" signal "IN6")
		(34 "In16.Cu" signal "GND7")
		(2 "B.Cu" signal "BOTTOM")
		(9 "F.Adhes" user "F.Adhesive")
		(11 "B.Adhes" user "B.Adhesive")
		(13 "F.Paste" user "Package Geometry/Pastemask Top")
		(15 "B.Paste" user "Package Geometry/Pastemask Bottom")
		(5 "F.SilkS" user "Ref Des/Silkscreen Top")
		(7 "B.SilkS" user "Ref Des/Silkscreen Bottom")
		(1 "F.Mask" user "Board Geometry/Soldermask Top")
		(3 "B.Mask" user "Board Geometry/Soldermask Bottom")
		(17 "Dwgs.User" user "User.Drawings")
		(19 "Cmts.User" user "User.Comments")
		(21 "Eco1.User" user "User.Eco1")
		(23 "Eco2.User" user "User.Eco2")
		(25 "Edge.Cuts" user "Board Geometry/Outline")
		(27 "Margin" user)
		(31 "F.CrtYd" user "Package Geometry/Place Bound Top")
		(29 "B.CrtYd" user "Package Geometry/Place Bound Bottom")
		(35 "F.Fab" user "Ref Des/Assembly Top")
		(33 "B.Fab" user "Ref Des/Assembly Bottom")
	)
	(footprint ""
		(layer "B.Cu")
		(at 348.913958 -249.36831 180)
		(property "Reference" "C2167"
			(at 0 0 0)
			(layer "B.SilkS")
			(hide yes)
			(effects
				(font
					(size 1.27 1.27)
				)
				(justify mirror)
			)
		)
		(property "Value" ""
			(at 0 0 0)
			(layer "B.Fab")
			(effects
				(font
					(size 1.27 1.27)
				)
				(justify mirror)
			)
		)
		(duplicate_pad_numbers_are_jumpers no)
		(fp_line
			(start 0.7874 0.4064)
			(end 0.7874 -0.4064)
			(stroke
				(width 0.1524)
				(type default)
			)
			(layer "B.SilkS")
		)
		(fp_line
			(start 0.7874 -0.4064)
			(end -0.7874 -0.4064)
			(stroke
				(width 0.1524)
				(type default)
			)
			(layer "B.SilkS")
		)
		(fp_line
			(start -0.7874 0.4064)
			(end 0.7874 0.4064)
			(stroke
				(width 0.1524)
				(type default)
			)
			(layer "B.SilkS")
		)
		(fp_line
			(start -0.7874 -0.4064)
			(end -0.7874 0.4064)
			(stroke
				(width 0.1524)
				(type default)
			)
			(layer "B.SilkS")
		)
		(fp_line
			(start 0.67945 0.3048)
			(end 0.67945 -0.305054)
			(stroke
				(width 0.1)
				(type default)
			)
			(layer "B.Fab")
		)
		(fp_line
			(start 0.67945 -0.305054)
			(end 0.12065 -0.305054)
			(stroke
				(width 0.1)
				(type default)
			)
			(layer "B.Fab")
		)
		(fp_line
			(start 0.12065 0.3048)
			(end 0.67945 0.3048)
			(stroke
				(width 0.1)
				(type default)
			)
			(layer "B.Fab")
		)
		(fp_line
			(start 0.12065 0.2794)
			(end 0.12065 0.3048)
			(stroke
				(width 0.1)
				(type default)
			)
			(layer "B.Fab")
		)
		(fp_line
			(start 0.12065 -0.2794)
			(end -0.12065 -0.2794)
			(stroke
				(width 0.1)
				(type default)
			)
			(layer "B.Fab")
		)
		(fp_line
			(start 0.12065 -0.305054)
			(end 0.12065 -0.2794)
			(stroke
				(width 0.1)
				(type default)
			)
			(layer "B.Fab")
		)
		(fp_line
			(start -0.120396 0.3048)
			(end -0.120396 0.2794)
			(stroke
				(width 0.1)
				(type default)
			)
			(layer "B.Fab")
		)
		(fp_line
			(start -0.120396 0.2794)
			(end 0.12065 0.2794)
			(stroke
				(width 0.1)
				(type default)
			)
			(layer "B.Fab")
		)
		(fp_line
			(start -0.12065 -0.2794)
			(end -0.12065 -0.3048)
			(stroke
				(width 0.1)
				(type default)
			)
			(layer "B.Fab")
		)
		(fp_line
			(start -0.12065 -0.3048)
			(end -0.67945 -0.3048)
			(stroke
				(width 0.1)
				(type default)
			)
			(layer "B.Fab")
		)
		(fp_line
			(start -0.67945 0.3048)
			(end -0.120396 0.3048)
			(stroke
				(width 0.1)
				(type default)
			)
			(layer "B.Fab")
		)
		(fp_line
			(start -0.67945 -0.3048)
			(end -0.67945 0.3048)
			(stroke
				(width 0.1)
				(type default)
			)
			(layer "B.Fab")
		)
		(pad "1" smd circle
			(at 0.40005 0)
			(size 0 0)
			(layers "B.Cu" "B.Mask" "B.Paste")
			(net "PVDDCR_CPU0_P0")
		)
		(pad "2" smd circle
			(at -0.40005 0)
			(size 0 0)
			(layers "B.Cu" "B.Mask" "B.Paste")
			(net "GND")
		)
	)
	(footprint ""
		(layer "B.Cu")
		(at 113.705386 -250.257564)
		(property "Reference" "C2316"
			(at 0 0 0)
			(layer "B.SilkS")
			(hide yes)
			(effects
				(font
					(size 1.27 1.27)
				)
				(justify mirror)
			)
		)
		(property "Value" ""
			(at 0 0 0)
			(layer "B.Fab")
			(effects
				(font
					(size 1.27 1.27)
				)
				(justify mirror)
			)
		)
		(duplicate_pad_numbers_are_jumpers no)
		(fp_line
			(start -0.7874 -0.4064)
			(end -0.7874 0.4064)
			(stroke
				(width 0.1524)
				(type default)
			)
			(layer "B.SilkS")
		)
		(fp_line
			(start -0.7874 0.4064)
			(end 0.7874 0.4064)
			(stroke
				(width 0.1524)
				(type default)
			)
			(layer "B.SilkS")
		)
		(fp_line
			(start 0.7874 -0.4064)
			(end -0.7874 -0.4064)
			(stroke
				(width 0.1524)
				(type default)
			)
			(layer "B.SilkS")
		)
		(fp_line
			(start 0.7874 0.4064)
			(end 0.7874 -0.4064)
			(stroke
				(width 0.1524)
				(type default)
			)
			(layer "B.SilkS")
		)
		(fp_line
			(start -0.67945 -0.3048)
			(end -0.67945 0.3048)
			(stroke
				(width 0.1)
				(type default)
			)
			(layer "B.Fab")
		)
		(fp_line
			(start -0.67945 0.3048)
			(end -0.120396 0.3048)
			(stroke
				(width 0.1)
				(type default)
			)
			(layer "B.Fab")
		)
		(fp_line
			(start -0.12065 -0.3048)
			(end -0.67945 -0.3048)
			(stroke
				(width 0.1)
				(type default)
			)
			(layer "B.Fab")
		)
		(fp_line
			(start -0.12065 -0.2794)
			(end -0.12065 -0.3048)
			(stroke
				(width 0.1)
				(type default)
			)
			(layer "B.Fab")
		)
		(fp_line
			(start -0.120396 0.2794)
			(end 0.12065 0.2794)
			(stroke
				(width 0.1)
				(type default)
			)
			(layer "B.Fab")
		)
		(fp_line
			(start -0.120396 0.3048)
			(end -0.120396 0.2794)
			(stroke
				(width 0.1)
				(type default)
			)
			(layer "B.Fab")
		)
		(fp_line
			(start 0.12065 -0.305054)
			(end 0.12065 -0.2794)
			(stroke
				(width 0.1)
				(type default)
			)
			(layer "B.Fab")
		)
		(fp_line
			(start 0.12065 -0.2794)
			(end -0.12065 -0.2794)
			(stroke
				(width 0.1)
				(type default)
			)
			(layer "B.Fab")
		)
		(fp_line
			(start 0.12065 0.2794)
			(end 0.12065 0.3048)
			(stroke
				(width 0.1)
				(type default)
			)
			(layer "B.Fab")
		)
		(fp_line
			(start 0.12065 0.3048)
			(end 0.67945 0.3048)
			(stroke
				(width 0.1)
				(type default)
			)
			(layer "B.Fab")
		)
		(fp_line
			(start 0.67945 -0.305054)
			(end 0.12065 -0.305054)
			(stroke
				(width 0.1)
				(type default)
			)
			(layer "B.Fab")
		)
		(fp_line
			(start 0.67945 0.3048)
			(end 0.67945 -0.305054)
			(stroke
				(width 0.1)
				(type default)
			)
			(layer "B.Fab")
		)
		(pad "1" smd circle
			(at 0.40005 0 180)
			(size 0 0)
			(layers "B.Cu" "B.Mask" "B.Paste")
			(net "PVDDCR_CPU0_P1")
		)
		(pad "2" smd circle
			(at -0.40005 0 180)
			(size 0 0)
			(layers "B.Cu" "B.Mask" "B.Paste")
			(net "GND")
		)
	)
	(footprint ""
		(layer "B.Cu")
		(at 303.172622 -393.88288 -90)
		(property "Reference" "C539"
			(at 0 0 90)
			(layer "B.SilkS")
			(hide yes)
			(effects
				(font
					(size 1.27 1.27)
				)
				(justify mirror)
			)
		)
		(property "Value" ""
			(at 0 0 90)
			(layer "B.Fab")
			(effects
				(font
					(size 1.27 1.27)
				)
				(justify mirror)
			)
		)
		(duplicate_pad_numbers_are_jumpers no)
		(fp_line
			(start -0.299974 0.150114)
			(end 0.299974 0.150114)
			(stroke
				(width 0.1)
				(type default)
			)
			(layer "B.Fab")
		)
		(fp_line
			(start 0.299974 0.150114)
			(end 0.299974 -0.150114)
			(stroke
				(width 0.1)
				(type default)
			)
			(layer "B.Fab")
		)
		(fp_line
			(start -0.299974 -0.150114)
			(end -0.299974 0.150114)
			(stroke
				(width 0.1)
				(type default)
			)
			(layer "B.Fab")
		)
		(fp_line
			(start 0.299974 -0.150114)
			(end -0.299974 -0.150114)
			(stroke
				(width 0.1)
				(type default)
			)
			(layer "B.Fab")
		)
		(pad "1" smd rect
			(at 0.2667 0 90)
			(size 0.3048 0.381)
			(layers "B.Cu" "B.Mask" "B.Paste")
			(net "P0V9_CPU0_RT0_2A")
		)
		(pad "2" smd rect
			(at -0.2667 0 90)
			(size 0.3048 0.381)
			(layers "B.Cu" "B.Mask" "B.Paste")
			(net "GND")
		)
	)
)
